# S9S_MB_2U (Grand Teton) — schematic netlist excerpt (pin names and nets, part order shuffled) for the footprints in the layout excerpt that follows; sources: Cadence DE-HDL packaged netlist, KiCad conversion of 03242023_DA0F0TMBIJ0_F0T_Motherboard_J_brd_V01_OCP.brd

C488  Q_CAP  47UF 2.5V 20% X6S  pkg C0603  page 78 : A = PVCCINFAON_CPU1 ; B = GND
PC618_P0_2  Q_CAP  22UF 4V 20% X6S  pkg C0805  page 271 : A = PVCCFA_EHV_FIVRA_CPU0 ; B = GND
PR1324  Q_RES  0 5% CHIP  pkg 0402LF  page 272 : A = PVCCFA_EHV_FIVRA_CPU0_VOS3 ; B = PVCCFA_EHV_FIVRA_CPU0

(kicad_pcb
	(version 20260206)
	(generator "pcbnew")
	(generator_version "10.0")
	(general
		(thickness 1.6)
		(legacy_teardrops no)
	)
	(paper "A4")
	(title_block
		(title "03242023_DA0F0TMBIJ0_F0T_Motherboard_J_brd_V01_OCP.brd")
		(comment 1 "Grand Teton / footprints 5980-5982 of 6105")
	)
	(layers
		(0 "F.Cu" signal "TOP")
		(4 "In1.Cu" signal "GND")
		(6 "In2.Cu" signal "IN1")
		(8 "In3.Cu" signal "GND1")
		(10 "In4.Cu" signal "IN2")
		(12 "In5.Cu" signal "GND2")
		(14 "In6.Cu" signal "IN3")
		(16 "In7.Cu" signal "GND3")
		(18 "In8.Cu" signal "VCC")
		(20 "In9.Cu" signal "VCC1")
		(22 "In10.Cu" signal "GND4")
		(24 "In11.Cu" signal "IN4")
		(26 "In12.Cu" signal "GND5")
		(28 "In13.Cu" signal "IN5")
		(30 "In14.Cu" signal "GND6")
		(32 "In15.Cu" signal "IN6")
		(34 "In16.Cu" signal "GND7")
		(2 "B.Cu" signal "BOTTOM")
		(9 "F.Adhes" user "F.Adhesive")
		(11 "B.Adhes" user "B.Adhesive")
		(13 "F.Paste" user "Package Geometry/Pastemask Top")
		(15 "B.Paste" user "Package Geometry/Pastemask Bottom")
		(5 "F.SilkS" user "Ref Des/Silkscreen Top")
		(7 "B.SilkS" user "Ref Des/Silkscreen Bottom")
		(1 "F.Mask" user "Board Geometry/Soldermask Top")
		(3 "B.Mask" user "Board Geometry/Soldermask Bottom")
		(17 "Dwgs.User" user "User.Drawings")
		(19 "Cmts.User" user "User.Comments")
		(21 "Eco1.User" user "User.Eco1")
		(23 "Eco2.User" user "User.Eco2")
		(25 "Edge.Cuts" user "Board Geometry/Outline")
		(27 "Margin" user)
		(31 "F.CrtYd" user "Package Geometry/Place Bound Top")
		(29 "B.CrtYd" user "Package Geometry/Place Bound Bottom")
		(35 "F.Fab" user "Ref Des/Assembly Top")
		(33 "B.Fab" user "Ref Des/Assembly Bottom")
	)
	(footprint ""
		(layer "B.Cu")
		(at 119.07012 -237.709456 -90)
		(property "Reference" "C488"
			(at 0 0 90)
			(layer "B.SilkS")
			(hide yes)
			(effects
				(font
					(size 1.27 1.27)
				)
				(justify mirror)
			)
		)
		(property "Value" ""
			(at 0 0 90)
			(layer "B.Fab")
			(effects
				(font
					(size 1.27 1.27)
				)
				(justify mirror)
			)
		)
		(duplicate_pad_numbers_are_jumpers no)
		(fp_line
			(start -1.2954 0.5842)
			(end 1.2954 0.5842)
			(stroke
				(width 0.1524)
				(type default)
			)
			(layer "B.SilkS")
		)
		(fp_line
			(start 1.2954 0.5842)
			(end 1.2954 -0.5842)
			(stroke
				(width 0.1524)
				(type default)
			)
			(layer "B.SilkS")
		)
		(fp_line
			(start -1.2954 -0.5842)
			(end -1.2954 0.5842)
			(stroke
				(width 0.1524)
				(type default)
			)
			(layer "B.SilkS")
		)
		(fp_line
			(start 0 -0.5842)
			(end 0 0.5842)
			(stroke
				(width 0.1524)
				(type default)
			)
			(layer "B.SilkS")
		)
		(fp_line
			(start 1.2954 -0.5842)
			(end -1.2954 -0.5842)
			(stroke
				(width 0.1524)
				(type default)
			)
			(layer "B.SilkS")
		)
		(fp_line
			(start -0.8636 0.4572)
			(end 0.8636 0.4572)
			(stroke
				(width 0.1)
				(type default)
			)
			(layer "B.Fab")
		)
		(fp_line
			(start 0.8636 0.4572)
			(end 0.8636 0.4064)
			(stroke
				(width 0.1)
				(type default)
			)
			(layer "B.Fab")
		)
		(fp_line
			(start -1.1938 0.4064)
			(end -0.8636 0.4064)
			(stroke
				(width 0.1)
				(type default)
			)
			(layer "B.Fab")
		)
		(fp_line
			(start -0.8636 0.4064)
			(end -0.8636 0.4572)
			(stroke
				(width 0.1)
				(type default)
			)
			(layer "B.Fab")
		)
		(fp_line
			(start 0.8636 0.4064)
			(end 1.1938 0.4064)
			(stroke
				(width 0.1)
				(type default)
			)
			(layer "B.Fab")
		)
		(fp_line
			(start 1.1938 0.4064)
			(end 1.1938 -0.4064)
			(stroke
				(width 0.1)
				(type default)
			)
			(layer "B.Fab")
		)
		(fp_line
			(start -1.1938 -0.4064)
			(end -1.1938 0.4064)
			(stroke
				(width 0.1)
				(type default)
			)
			(layer "B.Fab")
		)
		(fp_line
			(start -0.8636 -0.4064)
			(end -1.1938 -0.4064)
			(stroke
				(width 0.1)
				(type default)
			)
			(layer "B.Fab")
		)
		(fp_line
			(start 0.8636 -0.4064)
			(end 0.8636 -0.4572)
			(stroke
				(width 0.1)
				(type default)
			)
			(layer "B.Fab")
		)
		(fp_line
			(start 1.1938 -0.4064)
			(end 0.8636 -0.4064)
			(stroke
				(width 0.1)
				(type default)
			)
			(layer "B.Fab")
		)
		(fp_line
			(start -0.8636 -0.4572)
			(end -0.8636 -0.4064)
			(stroke
				(width 0.1)
				(type default)
			)
			(layer "B.Fab")
		)
		(fp_line
			(start 0.8636 -0.4572)
			(end -0.8636 -0.4572)
			(stroke
				(width 0.1)
				(type default)
			)
			(layer "B.Fab")
		)
		(pad "1" smd rect
			(at 0.7366 0 180)
			(size 0.7112 0.8128)
			(layers "B.Cu" "B.Mask" "B.Paste")
			(net "PVCCINFAON_CPU1")
		)
		(pad "2" smd rect
			(at -0.7366 0 180)
			(size 0.7112 0.8128)
			(layers "B.Cu" "B.Mask" "B.Paste")
			(net "GND")
		)
	)
	(footprint ""
		(layer "B.Cu")
		(at 303.09312 -353.878134 -90)
		(property "Reference" "PC618_P0_2"
			(at 0 0 90)
			(layer "B.SilkS")
			(hide yes)
			(effects
				(font
					(size 1.27 1.27)
				)
				(justify mirror)
			)
		)
		(property "Value" ""
			(at 0 0 90)
			(layer "B.Fab")
			(effects
				(font
					(size 1.27 1.27)
				)
				(justify mirror)
			)
		)
		(duplicate_pad_numbers_are_jumpers no)
		(fp_line
			(start -1.524 0.762)
			(end 1.524 0.762)
			(stroke
				(width 0.1524)
				(type default)
			)
			(layer "B.SilkS")
		)
		(fp_line
			(start 1.524 0.762)
			(end 1.524 -0.762)
			(stroke
				(width 0.1524)
				(type default)
			)
			(layer "B.SilkS")
		)
		(fp_line
			(start -1.524 -0.762)
			(end -1.524 0.762)
			(stroke
				(width 0.1524)
				(type default)
			)
			(layer "B.SilkS")
		)
		(fp_line
			(start 1.524 -0.762)
			(end -1.524 -0.762)
			(stroke
				(width 0.1524)
				(type default)
			)
			(layer "B.SilkS")
		)
		(fp_line
			(start -1.1049 0.724916)
			(end -1.1049 -0.724916)
			(stroke
				(width 0.1)
				(type default)
			)
			(layer "B.Fab")
		)
		(fp_line
			(start 1.1049 0.724916)
			(end -1.1049 0.724916)
			(stroke
				(width 0.1)
				(type default)
			)
			(layer "B.Fab")
		)
		(fp_line
			(start -1.1049 -0.724916)
			(end 1.1049 -0.724916)
			(stroke
				(width 0.1)
				(type default)
			)
			(layer "B.Fab")
		)
		(fp_line
			(start 1.1049 -0.724916)
			(end 1.1049 0.724916)
			(stroke
				(width 0.1)
				(type default)
			)
			(layer "B.Fab")
		)
		(pad "1" smd rect
			(at 0.889 0 270)
			(size 1.016 1.27)
			(layers "B.Cu" "B.Mask" "B.Paste")
			(net "PVCCFA_EHV_FIVRA_CPU0")
		)
		(pad "2" smd rect
			(at -0.889 0 270)
			(size 1.016 1.27)
			(layers "B.Cu" "B.Mask" "B.Paste")
			(net "GND")
		)
	)
	(footprint ""
		(layer "B.Cu")
		(at 423.079164 -366.466374 -90)
		(property "Reference" "PR1324"
			(at 0 0 90)
			(layer "B.SilkS")
			(hide yes)
			(effects
				(font
					(size 1.27 1.27)
				)
				(justify mirror)
			)
		)
		(property "Value" ""
			(at 0 0 90)
			(layer "B.Fab")
			(effects
				(font
					(size 1.27 1.27)
				)
				(justify mirror)
			)
		)
		(duplicate_pad_numbers_are_jumpers no)
		(fp_line
			(start -0.7874 0.4064)
			(end 0.7874 0.4064)
			(stroke
				(width 0.1524)
				(type default)
			)
			(layer "B.SilkS")
		)
		(fp_line
			(start 0.7874 0.4064)
			(end 0.7874 -0.4064)
			(stroke
				(width 0.1524)
				(type default)
			)
			(layer "B.SilkS")
		)
		(fp_line
			(start -0.7874 -0.4064)
			(end -0.7874 0.4064)
			(stroke
				(width 0.1524)
				(type default)
			)
			(layer "B.SilkS")
		)
		(fp_line
			(start 0.7874 -0.4064)
			(end -0.7874 -0.4064)
			(stroke
				(width 0.1524)
				(type default)
			)
			(layer "B.SilkS")
		)
		(fp_line
			(start -0.67945 0.3048)
			(end -0.120396 0.3048)
			(stroke
				(width 0.1)
				(type default)
			)
			(layer "B.Fab")
		)
		(fp_line
			(start -0.120396 0.3048)
			(end -0.120396 0.2794)
			(stroke
				(width 0.1)
				(type default)
			)
			(layer "B.Fab")
		)
		(fp_line
			(start 0.12065 0.3048)
			(end 0.67945 0.3048)
			(stroke
				(width 0.1)
				(type default)
			)
			(layer "B.Fab")
		)
		(fp_line
			(start 0.67945 0.3048)
			(end 0.67945 -0.305054)
			(stroke
				(width 0.1)
				(type default)
			)
			(layer "B.Fab")
		)
		(fp_line
			(start -0.120396 0.2794)
			(end 0.12065 0.2794)
			(stroke
				(width 0.1)
				(type default)
			)
			(layer "B.Fab")
		)
		(fp_line
			(start 0.12065 0.2794)
			(end 0.12065 0.3048)
			(stroke
				(width 0.1)
				(type default)
			)
			(layer "B.Fab")
		)
		(fp_line
			(start -0.12065 -0.2794)
			(end -0.12065 -0.3048)
			(stroke
				(width 0.1)
				(type default)
			)
			(layer "B.Fab")
		)
		(fp_line
			(start 0.12065 -0.2794)
			(end -0.12065 -0.2794)
			(stroke
				(width 0.1)
				(type default)
			)
			(layer "B.Fab")
		)
		(fp_line
			(start -0.67945 -0.3048)
			(end -0.67945 0.3048)
			(stroke
				(width 0.1)
				(type default)
			)
			(layer "B.Fab")
		)
		(fp_line
			(start -0.12065 -0.3048)
			(end -0.67945 -0.3048)
			(stroke
				(width 0.1)
				(type default)
			)
			(layer "B.Fab")
		)
		(fp_line
			(start 0.12065 -0.305054)
			(end 0.12065 -0.2794)
			(stroke
				(width 0.1)
				(type default)
			)
			(layer "B.Fab")
		)
		(fp_line
			(start 0.67945 -0.305054)
			(end 0.12065 -0.305054)
			(stroke
				(width 0.1)
				(type default)
			)
			(layer "B.Fab")
		)
		(pad "1" smd circle
			(at 0.40005 0 90)
			(size 0 0)
			(layers "B.Cu" "B.Mask" "B.Paste")
			(net "PVCCFA_EHV_FIVRA_CPU0_VOS3")
		)
		(pad "2" smd circle
			(at -0.40005 0 90)
			(size 0 0)
			(layers "B.Cu" "B.Mask" "B.Paste")
			(net "PVCCFA_EHV_FIVRA_CPU0")
		)
	)
)
